(kicad_pcb
	(version 20260206)
	(generator "pcbnew")
	(generator_version "10.0")
	(general
		(thickness 1.6)
		(legacy_teardrops no)
	)
	(paper "A4")
	(title_block
		(title "Wiwynn_Tioga_Pass_MB.brd")
		(comment 1 "Tioga Pass / footprint 2018 of 4770 (J1G1), pads 244-291 of 291")
	)
	(layers
		(0 "F.Cu" signal "TOP")
		(4 "In1.Cu" signal "L2GND")
		(6 "In2.Cu" signal "L3")
		(8 "In3.Cu" signal "L4GND")
		(10 "In4.Cu" signal "L5")
		(12 "In5.Cu" signal "L6GND")
		(14 "In6.Cu" signal "L7VCC")
		(16 "In7.Cu" signal "L8VCC")
		(18 "In8.Cu" signal "L9GND")
		(20 "In9.Cu" signal "L10")
		(22 "In10.Cu" signal "L11GND")
		(24 "In11.Cu" signal "L12")
		(26 "In12.Cu" signal "L13GND")
		(2 "B.Cu" signal "BOTTOM")
		(9 "F.Adhes" user "F.Adhesive")
		(11 "B.Adhes" user "B.Adhesive")
		(13 "F.Paste" user "Package Geometry/Pastemask Top")
		(15 "B.Paste" user "Package Geometry/Pastemask Bottom")
		(5 "F.SilkS" user "Ref Des/Silkscreen Top")
		(7 "B.SilkS" user "Ref Des/Silkscreen Bottom")
		(1 "F.Mask" user "Board Geometry/Soldermask Top")
		(3 "B.Mask" user "Board Geometry/Soldermask Bottom")
		(17 "Dwgs.User" user "User.Drawings")
		(19 "Cmts.User" user "User.Comments")
		(21 "Eco1.User" user "User.Eco1")
		(23 "Eco2.User" user "User.Eco2")
		(25 "Edge.Cuts" user "Board Geometry/Outline")
		(27 "Margin" user)
		(31 "F.CrtYd" user "Package Geometry/Place Bound Top")
		(29 "B.CrtYd" user "Package Geometry/Place Bound Bottom")
		(35 "F.Fab" user "Ref Des/Assembly Top")
		(33 "B.Fab" user "Ref Des/Assembly Bottom")
	)
	(footprint ""
		(layer "F.Cu")
		(at 29.699458 -15.423642 90)
		(property "Reference" "J1G1"
			(at 9.314688 35.070542 0)
			(unlocked yes)
			(layer "F.SilkS")
			(effects
				(font
					(size 0.7874 0.5842)
					(thickness 0.1524)
				)
				(justify left)
			)
		)
		(property "Value" ""
			(at 0 0 90)
			(layer "F.Fab")
			(effects
				(font
					(size 1.27 1.27)
				)
			)
		)
		(duplicate_pad_numbers_are_jumpers no)
		(pad "241" smd rect
			(at 4.59994 86.700106 90)
			(size 1.8034 0.508)
			(layers "F.Cu" "F.Mask" "F.Paste")
			(net "GND")
		)
		(pad "242" smd rect
			(at 4.59994 87.54999 90)
			(size 1.8034 0.508)
			(layers "F.Cu" "F.Mask" "F.Paste")
			(net "M_G_DQ<32>")
		)
		(pad "243" smd rect
			(at 4.59994 88.399874 90)
			(size 1.8034 0.508)
			(layers "F.Cu" "F.Mask" "F.Paste")
			(net "GND")
		)
		(pad "244" smd rect
			(at 4.59994 89.250012 90)
			(size 1.8034 0.508)
			(layers "F.Cu" "F.Mask" "F.Paste")
			(net "M_G_DQS_DN<4>")
		)
		(pad "245" smd rect
			(at 4.59994 90.099896 90)
			(size 1.8034 0.508)
			(layers "F.Cu" "F.Mask" "F.Paste")
			(net "M_G_DQS_DP<4>")
		)
		(pad "246" smd rect
			(at 4.59994 90.950034 90)
			(size 1.8034 0.508)
			(layers "F.Cu" "F.Mask" "F.Paste")
			(net "GND")
		)
		(pad "247" smd rect
			(at 4.59994 91.799918 90)
			(size 1.8034 0.508)
			(layers "F.Cu" "F.Mask" "F.Paste")
			(net "M_G_DQ<38>")
		)
		(pad "248" smd rect
			(at 4.59994 92.650056 90)
			(size 1.8034 0.508)
			(layers "F.Cu" "F.Mask" "F.Paste")
			(net "GND")
		)
		(pad "249" smd rect
			(at 4.59994 93.49994 90)
			(size 1.8034 0.508)
			(layers "F.Cu" "F.Mask" "F.Paste")
			(net "M_G_DQ<34>")
		)
		(pad "250" smd rect
			(at 4.59994 94.350078 90)
			(size 1.8034 0.508)
			(layers "F.Cu" "F.Mask" "F.Paste")
			(net "GND")
		)
		(pad "251" smd rect
			(at 4.59994 95.199962 90)
			(size 1.8034 0.508)
			(layers "F.Cu" "F.Mask" "F.Paste")
			(net "M_G_DQ<44>")
		)
		(pad "252" smd rect
			(at 4.59994 96.0501 90)
			(size 1.8034 0.508)
			(layers "F.Cu" "F.Mask" "F.Paste")
			(net "GND")
		)
		(pad "253" smd rect
			(at 4.59994 96.899984 90)
			(size 1.8034 0.508)
			(layers "F.Cu" "F.Mask" "F.Paste")
			(net "M_G_DQ<40>")
		)
		(pad "254" smd rect
			(at 4.59994 97.750122 90)
			(size 1.8034 0.508)
			(layers "F.Cu" "F.Mask" "F.Paste")
			(net "GND")
		)
		(pad "255" smd rect
			(at 4.59994 98.600006 90)
			(size 1.8034 0.508)
			(layers "F.Cu" "F.Mask" "F.Paste")
			(net "M_G_DQS_DN<5>")
		)
		(pad "256" smd rect
			(at 4.59994 99.44989 90)
			(size 1.8034 0.508)
			(layers "F.Cu" "F.Mask" "F.Paste")
			(net "M_G_DQS_DP<5>")
		)
		(pad "257" smd rect
			(at 4.59994 100.300028 90)
			(size 1.8034 0.508)
			(layers "F.Cu" "F.Mask" "F.Paste")
			(net "GND")
		)
		(pad "258" smd rect
			(at 4.59994 101.149912 90)
			(size 1.8034 0.508)
			(layers "F.Cu" "F.Mask" "F.Paste")
			(net "M_G_DQ<46>")
		)
		(pad "259" smd rect
			(at 4.59994 102.00005 90)
			(size 1.8034 0.508)
			(layers "F.Cu" "F.Mask" "F.Paste")
			(net "GND")
		)
		(pad "260" smd rect
			(at 4.59994 102.849934 90)
			(size 1.8034 0.508)
			(layers "F.Cu" "F.Mask" "F.Paste")
			(net "M_G_DQ<42>")
		)
		(pad "261" smd rect
			(at 4.59994 103.700072 90)
			(size 1.8034 0.508)
			(layers "F.Cu" "F.Mask" "F.Paste")
			(net "GND")
		)
		(pad "262" smd rect
			(at 4.59994 104.549956 90)
			(size 1.8034 0.508)
			(layers "F.Cu" "F.Mask" "F.Paste")
			(net "M_G_DQ<52>")
		)
		(pad "263" smd rect
			(at 4.59994 105.400094 90)
			(size 1.8034 0.508)
			(layers "F.Cu" "F.Mask" "F.Paste")
			(net "GND")
		)
		(pad "264" smd rect
			(at 4.59994 106.249978 90)
			(size 1.8034 0.508)
			(layers "F.Cu" "F.Mask" "F.Paste")
			(net "M_G_DQ<48>")
		)
		(pad "265" smd rect
			(at 4.59994 107.100116 90)
			(size 1.8034 0.508)
			(layers "F.Cu" "F.Mask" "F.Paste")
			(net "GND")
		)
		(pad "266" smd rect
			(at 4.59994 107.95 90)
			(size 1.8034 0.508)
			(layers "F.Cu" "F.Mask" "F.Paste")
			(net "M_G_DQS_DN<6>")
		)
		(pad "267" smd rect
			(at 4.59994 108.799884 90)
			(size 1.8034 0.508)
			(layers "F.Cu" "F.Mask" "F.Paste")
			(net "M_G_DQS_DP<6>")
		)
		(pad "268" smd rect
			(at 4.59994 109.650022 90)
			(size 1.8034 0.508)
			(layers "F.Cu" "F.Mask" "F.Paste")
			(net "GND")
		)
		(pad "269" smd rect
			(at 4.59994 110.499906 90)
			(size 1.8034 0.508)
			(layers "F.Cu" "F.Mask" "F.Paste")
			(net "M_G_DQ<54>")
		)
		(pad "270" smd rect
			(at 4.59994 111.350044 90)
			(size 1.8034 0.508)
			(layers "F.Cu" "F.Mask" "F.Paste")
			(net "GND")
		)
		(pad "271" smd rect
			(at 4.59994 112.199928 90)
			(size 1.8034 0.508)
			(layers "F.Cu" "F.Mask" "F.Paste")
			(net "M_G_DQ<50>")
		)
		(pad "272" smd rect
			(at 4.59994 113.050066 90)
			(size 1.8034 0.508)
			(layers "F.Cu" "F.Mask" "F.Paste")
			(net "GND")
		)
		(pad "273" smd rect
			(at 4.59994 113.89995 90)
			(size 1.8034 0.508)
			(layers "F.Cu" "F.Mask" "F.Paste")
			(net "M_G_DQ<60>")
		)
		(pad "274" smd rect
			(at 4.59994 114.750088 90)
			(size 1.8034 0.508)
			(layers "F.Cu" "F.Mask" "F.Paste")
			(net "GND")
		)
		(pad "275" smd rect
			(at 4.59994 115.599972 90)
			(size 1.8034 0.508)
			(layers "F.Cu" "F.Mask" "F.Paste")
			(net "M_G_DQ<56>")
		)
		(pad "276" smd rect
			(at 4.59994 116.45011 90)
			(size 1.8034 0.508)
			(layers "F.Cu" "F.Mask" "F.Paste")
			(net "GND")
		)
		(pad "277" smd rect
			(at 4.59994 117.299994 90)
			(size 1.8034 0.508)
			(layers "F.Cu" "F.Mask" "F.Paste")
			(net "M_G_DQS_DN<7>")
		)
		(pad "278" smd rect
			(at 4.59994 118.149878 90)
			(size 1.8034 0.508)
			(layers "F.Cu" "F.Mask" "F.Paste")
			(net "M_G_DQS_DP<7>")
		)
		(pad "279" smd rect
			(at 4.59994 119.000016 90)
			(size 1.8034 0.508)
			(layers "F.Cu" "F.Mask" "F.Paste")
			(net "GND")
		)
		(pad "280" smd rect
			(at 4.59994 119.8499 90)
			(size 1.8034 0.508)
			(layers "F.Cu" "F.Mask" "F.Paste")
			(net "M_G_DQ<62>")
		)
		(pad "281" smd rect
			(at 4.59994 120.700038 90)
			(size 1.8034 0.508)
			(layers "F.Cu" "F.Mask" "F.Paste")
			(net "GND")
		)
		(pad "282" smd rect
			(at 4.59994 121.549922 90)
			(size 1.8034 0.508)
			(layers "F.Cu" "F.Mask" "F.Paste")
			(net "M_G_DQ<58>")
		)
		(pad "283" smd rect
			(at 4.59994 122.40006 90)
			(size 1.8034 0.508)
			(layers "F.Cu" "F.Mask" "F.Paste")
			(net "GND")
		)
		(pad "284" smd rect
			(at 4.59994 123.249944 90)
			(size 1.8034 0.508)
			(layers "F.Cu" "F.Mask" "F.Paste")
			(net "PVPP_GHJ")
		)
		(pad "285" smd rect
			(at 4.59994 124.100082 90)
			(size 1.8034 0.508)
			(layers "F.Cu" "F.Mask" "F.Paste")
			(net "SMB_DDR_GHJ_VPP_SDA")
		)
		(pad "286" smd rect
			(at 4.59994 124.949966 90)
			(size 1.8034 0.508)
			(layers "F.Cu" "F.Mask" "F.Paste")
			(net "PVPP_GHJ")
		)
		(pad "287" smd rect
			(at 4.59994 125.800104 90)
			(size 1.8034 0.508)
			(layers "F.Cu" "F.Mask" "F.Paste")
			(net "PVPP_GHJ")
		)
		(pad "288" smd rect
			(at 4.59994 126.649988 90)
			(size 1.8034 0.508)
			(layers "F.Cu" "F.Mask" "F.Paste")
			(net "PVPP_GHJ")
		)
	)
)
